FILE_TYPE = CONNECTIVITY;
{Allegro Design Entry HDL 17.2-2016 S081 (4005846) 1/11/2022}
"PAGE_NUMBER" = 50;
0"NC";
1"GMI_CPU1_G2_CPU0_G0_TX_DN<15:0>";
2"GMI_CPU1_G2_CPU0_G0_TX_DP<15:0>";
3"GMI_CPU1_G3_CPU0_G1_TX_DN<15:0>";
4"GMI_CPU1_G3_CPU0_G1_TX_DP<15:0>";
5"GMI_CPU0_G0_CPU1_G2_TX_DP<15:0>";
6"GMI_CPU0_G0_CPU1_G2_TX_DN<15:0>";
7"GMI_CPU0_G1_CPU1_G3_TX_DP<15:0>";
8"GMI_CPU0_G1_CPU1_G3_TX_DN<15:0>";
9"GMI_CPU0_G1_CPU1_G3_TX_DN<13>";
10"GMI_CPU0_G1_CPU1_G3_TX_DN<3>";
11"GMI_CPU0_G1_CPU1_G3_TX_DN<0>";
12"GMI_CPU0_G1_CPU1_G3_TX_DN<6>";
13"GMI_CPU0_G1_CPU1_G3_TX_DP<13>";
14"GMI_CPU0_G1_CPU1_G3_TX_DP<10>";
15"GMI_CPU0_G1_CPU1_G3_TX_DP<1>";
16"GMI_CPU0_G1_CPU1_G3_TX_DP<4>";
17"GMI_CPU0_G1_CPU1_G3_TX_DN<14>";
18"GMI_CPU0_G1_CPU1_G3_TX_DN<11>";
19"GMI_CPU0_G1_CPU1_G3_TX_DN<8>";
20"GMI_CPU0_G1_CPU1_G3_TX_DP<6>";
21"GMI_CPU0_G1_CPU1_G3_TX_DN<4>";
22"GMI_CPU0_G1_CPU1_G3_TX_DN<1>";
23"GMI_CPU0_G1_CPU1_G3_TX_DP<8>";
24"GMI_CPU0_G1_CPU1_G3_TX_DN<7>";
25"GMI_CPU0_G1_CPU1_G3_TX_DP<14>";
26"GMI_CPU0_G1_CPU1_G3_TX_DP<11>";
27"GMI_CPU0_G1_CPU1_G3_TX_DP<5>";
28"GMI_CPU0_G1_CPU1_G3_TX_DP<2>";
29"GMI_CPU0_G1_CPU1_G3_TX_DN<9>";
30"GMI_CPU0_G1_CPU1_G3_TX_DN<15>";
31"GMI_CPU0_G1_CPU1_G3_TX_DN<12>";
32"GMI_CPU0_G1_CPU1_G3_TX_DP<7>";
33"GMI_CPU0_G1_CPU1_G3_TX_DN<2>";
34"GMI_CPU0_G1_CPU1_G3_TX_DN<5>";
35"GMI_CPU0_G1_CPU1_G3_TX_DP<12>";
36"GMI_CPU0_G1_CPU1_G3_TX_DP<9>";
37"GMI_CPU0_G1_CPU1_G3_TX_DP<0>";
38"GMI_CPU0_G1_CPU1_G3_TX_DP<15>";
39"GMI_CPU0_G1_CPU1_G3_TX_DP<3>";
40"GMI_CPU0_G1_CPU1_G3_TX_DN<10>";
41"GMI_CPU0_G0_CPU1_G2_TX_DN<8>";
42"GMI_CPU0_G0_CPU1_G2_TX_DN<9>";
43"GMI_CPU0_G0_CPU1_G2_TX_DN<10>";
44"GMI_CPU0_G0_CPU1_G2_TX_DP<8>";
45"GMI_CPU0_G0_CPU1_G2_TX_DN<11>";
46"GMI_CPU0_G0_CPU1_G2_TX_DP<9>";
47"GMI_CPU0_G0_CPU1_G2_TX_DN<12>";
48"GMI_CPU0_G0_CPU1_G2_TX_DP<10>";
49"GMI_CPU0_G0_CPU1_G2_TX_DN<13>";
50"GMI_CPU0_G0_CPU1_G2_TX_DP<11>";
51"GMI_CPU0_G0_CPU1_G2_TX_DN<14>";
52"GMI_CPU0_G0_CPU1_G2_TX_DP<12>";
53"GMI_CPU0_G0_CPU1_G2_TX_DN<15>";
54"GMI_CPU0_G0_CPU1_G2_TX_DP<13>";
55"GMI_CPU0_G0_CPU1_G2_TX_DP<14>";
56"GMI_CPU0_G0_CPU1_G2_TX_DP<15>";
57"GMI_CPU0_G0_CPU1_G2_TX_DN<0>";
58"GMI_CPU0_G0_CPU1_G2_TX_DP<0>";
59"GMI_CPU0_G0_CPU1_G2_TX_DN<2>";
60"GMI_CPU0_G0_CPU1_G2_TX_DP<2>";
61"GMI_CPU0_G0_CPU1_G2_TX_DN<4>";
62"GMI_CPU0_G0_CPU1_G2_TX_DP<4>";
63"GMI_CPU0_G0_CPU1_G2_TX_DN<6>";
64"GMI_CPU0_G0_CPU1_G2_TX_DP<6>";
65"GMI_CPU0_G0_CPU1_G2_TX_DN<1>";
66"GMI_CPU0_G0_CPU1_G2_TX_DP<1>";
67"GMI_CPU0_G0_CPU1_G2_TX_DN<3>";
68"GMI_CPU0_G0_CPU1_G2_TX_DP<3>";
69"GMI_CPU0_G0_CPU1_G2_TX_DN<5>";
70"GMI_CPU0_G0_CPU1_G2_TX_DP<5>";
71"GMI_CPU0_G0_CPU1_G2_TX_DN<7>";
72"GMI_CPU0_G0_CPU1_G2_TX_DP<7>";
73"GMI_CPU1_G3_CPU0_G1_TX_DP<0>";
74"GMI_CPU1_G3_CPU0_G1_TX_DP<3>";
75"GMI_CPU1_G3_CPU0_G1_TX_DP<1>";
76"GMI_CPU1_G3_CPU0_G1_TX_DP<4>";
77"GMI_CPU1_G3_CPU0_G1_TX_DP<2>";
78"GMI_CPU1_G3_CPU0_G1_TX_DN<2>";
79"GMI_CPU1_G3_CPU0_G1_TX_DN<3>";
80"GMI_CPU1_G3_CPU0_G1_TX_DN<0>";
81"GMI_CPU1_G3_CPU0_G1_TX_DN<4>";
82"GMI_CPU1_G3_CPU0_G1_TX_DN<1>";
83"GMI_CPU1_G3_CPU0_G1_TX_DP<6>";
84"GMI_CPU1_G3_CPU0_G1_TX_DP<8>";
85"GMI_CPU1_G3_CPU0_G1_TX_DP<7>";
86"GMI_CPU1_G3_CPU0_G1_TX_DP<9>";
87"GMI_CPU1_G3_CPU0_G1_TX_DP<5>";
88"GMI_CPU1_G3_CPU0_G1_TX_DP<10>";
89"GMI_CPU1_G3_CPU0_G1_TX_DP<13>";
90"GMI_CPU1_G3_CPU0_G1_TX_DP<14>";
91"GMI_CPU1_G3_CPU0_G1_TX_DP<11>";
92"GMI_CPU1_G3_CPU0_G1_TX_DP<12>";
93"GMI_CPU1_G3_CPU0_G1_TX_DP<15>";
94"GMI_CPU1_G3_CPU0_G1_TX_DN<6>";
95"GMI_CPU1_G3_CPU0_G1_TX_DN<11>";
96"GMI_CPU1_G3_CPU0_G1_TX_DN<8>";
97"GMI_CPU1_G3_CPU0_G1_TX_DN<5>";
98"GMI_CPU1_G3_CPU0_G1_TX_DN<14>";
99"GMI_CPU1_G3_CPU0_G1_TX_DN<7>";
100"GMI_CPU1_G3_CPU0_G1_TX_DN<12>";
101"GMI_CPU1_G3_CPU0_G1_TX_DN<9>";
102"GMI_CPU1_G3_CPU0_G1_TX_DN<15>";
103"GMI_CPU1_G3_CPU0_G1_TX_DN<10>";
104"GMI_CPU1_G3_CPU0_G1_TX_DN<13>";
105"GMI_CPU1_G2_CPU0_G0_TX_DP<0>";
106"GMI_CPU1_G2_CPU0_G0_TX_DP<2>";
107"GMI_CPU1_G2_CPU0_G0_TX_DP<1>";
108"GMI_CPU1_G2_CPU0_G0_TX_DP<3>";
109"GMI_CPU1_G2_CPU0_G0_TX_DP<8>";
110"GMI_CPU1_G2_CPU0_G0_TX_DP<4>";
111"GMI_CPU1_G2_CPU0_G0_TX_DP<6>";
112"GMI_CPU1_G2_CPU0_G0_TX_DP<5>";
113"GMI_CPU1_G2_CPU0_G0_TX_DP<7>";
114"GMI_CPU1_G2_CPU0_G0_TX_DP<9>";
115"GMI_CPU1_G2_CPU0_G0_TX_DP<10>";
116"GMI_CPU1_G2_CPU0_G0_TX_DP<11>";
117"GMI_CPU1_G2_CPU0_G0_TX_DP<12>";
118"GMI_CPU1_G2_CPU0_G0_TX_DP<13>";
119"GMI_CPU1_G2_CPU0_G0_TX_DP<15>";
120"GMI_CPU1_G2_CPU0_G0_TX_DP<14>";
121"GMI_CPU1_G2_CPU0_G0_TX_DN<8>";
122"GMI_CPU1_G2_CPU0_G0_TX_DN<9>";
123"GMI_CPU1_G2_CPU0_G0_TX_DN<10>";
124"GMI_CPU1_G2_CPU0_G0_TX_DN<11>";
125"GMI_CPU1_G2_CPU0_G0_TX_DN<12>";
126"GMI_CPU1_G2_CPU0_G0_TX_DN<13>";
127"GMI_CPU1_G2_CPU0_G0_TX_DN<14>";
128"GMI_CPU1_G2_CPU0_G0_TX_DN<15>";
129"GMI_CPU1_G2_CPU0_G0_TX_DN<0>";
130"GMI_CPU1_G2_CPU0_G0_TX_DN<2>";
131"GMI_CPU1_G2_CPU0_G0_TX_DN<4>";
132"GMI_CPU1_G2_CPU0_G0_TX_DN<6>";
133"GMI_CPU1_G2_CPU0_G0_TX_DN<1>";
134"GMI_CPU1_G2_CPU0_G0_TX_DN<3>";
135"GMI_CPU1_G2_CPU0_G0_TX_DN<5>";
136"GMI_CPU1_G2_CPU0_G0_TX_DN<7>";
%"GENOA_SP5"
"13","(-4750,5050)","0","pure_quanta","I143";
;
LOCATION"U26"
$SEC"13"
CDS_SEC"13"
PART_TYPE"SMLF"
MATERIAL"IO"
VALUE"SOCKET6096_13568-001"
PART_NUMBER"DGA^6000030"
CDS_LIB"pure_quanta"
NEEDS_NO_SIZE"TRUE"
CDS_LMAN_SYM_OUTLINE"-1100,950,1100,-950";
"G2_TXP0"
$PN"N23"119;
"G2_RXN7"
$PN"AC29"41;
"G2_RXN6"
$PN"AE29"42;
"G2_RXN5"
$PN"AG26"43;
"G2_RXP7"
$PN"AC30"44;
"G2_TXN7"
$PN"J30"121;
"G2_RXN4"
$PN"AC26"45;
"G2_RXP6"
$PN"AE30"46;
"G2_TXN6"
$PN"L27"122;
"G2_RXN3"
$PN"AE26"47;
"G2_RXP5"
$PN"AG27"48;
"G2_TXN5"
$PN"G27"123;
"G2_TXP7"
$PN"J29"109;
"G2_RXN2"
$PN"AG23"49;
"G2_RXP4"
$PN"AC27"50;
"G2_TXN4"
$PN"J27"124;
"G2_TXP6"
$PN"L26"114;
"G2_RXN1"
$PN"AC23"51;
"G2_RXP3"
$PN"AE27"52;
"G2_TXN3"
$PN"L24"125;
"G2_TXP5"
$PN"G26"115;
"G2_RXN0"
$PN"AE23"53;
"G2_RXP2"
$PN"AG24"54;
"G2_TXN2"
$PN"G24"126;
"G2_TXP4"
$PN"J26"116;
"G2_RXP1"
$PN"AC24"55;
"G2_TXN1"
$PN"J24"127;
"G2_TXP3"
$PN"L23"117;
"G2_RXP0"
$PN"AE24"56;
"G2_TXN0"
$PN"N24"128;
"G2_TXP2"
$PN"G23"118;
"G2_TXP1"
$PN"J23"120;
"G2_RXN15"
$PN"AF35"57;
"G2_RXP15"
$PN"AF36"58;
"G2_RXN13"
$PN"AB35"59;
"G2_RXP13"
$PN"AB36"60;
"G2_RXN11"
$PN"AA32"61;
"G2_RXP11"
$PN"AA33"62;
"G2_RXN9"
$PN"AE32"63;
"G2_RXP9"
$PN"AE33"64;
"G2_RXN14"
$PN"AD35"65;
"G2_RXP14"
$PN"AD36"66;
"G2_RXN12"
$PN"AG32"67;
"G2_RXP12"
$PN"AG33"68;
"G2_RXN10"
$PN"AC32"69;
"G2_RXP10"
$PN"AC33"70;
"G2_RXN8"
$PN"AG29"71;
"G2_RXP8"
$PN"AG30"72;
"G2_TXN15"
$PN"M36"129;
"G2_TXP15"
$PN"M35"105;
"G2_TXN13"
$PN"H36"130;
"G2_TXP13"
$PN"H35"106;
"G2_TXN11"
$PN"G33"131;
"G2_TXP11"
$PN"G32"110;
"G2_TXN9"
$PN"L30"132;
"G2_TXP9"
$PN"L29"111;
"G2_TXN14"
$PN"K36"133;
"G2_TXP14"
$PN"K35"107;
"G2_TXN12"
$PN"L33"134;
"G2_TXP12"
$PN"L32"108;
"G2_TXN10"
$PN"J33"135;
"G2_TXP10"
$PN"J32"112;
"G2_TXN8"
$PN"G30"136;
"G2_TXP8"
$PN"G29"113;
%"GENOA_SP5"
"14","(-4725,2375)","0","pure_quanta","I144";
;
LOCATION"U26"
$SEC"14"
CDS_SEC"14"
PART_TYPE"SMLF"
MATERIAL"IO"
VALUE"SOCKET6096_13568-001"
PART_NUMBER"DGA^6000030"
CDS_LIB"pure_quanta"
NEEDS_NO_SIZE"TRUE"
CDS_LMAN_SYM_OUTLINE"-1100,950,1100,-950";
"G3_RXN2||SATA22_RXN"
$PN"AN23"9;
"G3_TXN9||SATA31_TXN"
$PN"U30"94;
"G3_RXN12||SATA34_RXN"
$PN"AK35"10;
"G3_RXN15||SATA37_RXN"
$PN"AP35"11;
"G3_TXP5||SATA25_TXP"
$PN"N26"88;
"G3_RXN9||SATA31_RXN"
$PN"AL32"12;
"G3_TXP2||SATA22_TXP"
$PN"W23"89;
"G3_RXP2||SATA22_RXP"
$PN"AN24"13;
"G3_RXP5||SATA25_RXP"
$PN"AN27"14;
"G3_RXP14||SATA36_RXP"
$PN"AM36"15;
"G3_TXN4||SATA24_TXN"
$PN"R27"95;
"G3_TXN7||SATA27_TXN"
$PN"R30"96;
"G3_TXN10||SATA32_TXN"
$PN"R33"97;
"G3_TXN13||SATA35_TXN"
$PN"P36"78;
"G3_RXP11||SATA33_RXP"
$PN"AN33"16;
"G3_TXN1||SATA21_TXN"
$PN"R24"98;
"G3_TXP9||SATA31_TXP"
$PN"U29"83;
"G3_TXP15||SATA37_TXP"
$PN"V35"73;
"G3_RXN1||SATA21_RXN"
$PN"AJ23"17;
"G3_RXN4||SATA24_RXN"
$PN"AJ26"18;
"G3_RXN7||SATA27_RXN"
$PN"AJ29"19;
"G3_TXP12||SATA34_TXP"
$PN"U32"74;
"G3_RXP9||SATA31_RXP"
$PN"AL33"20;
"G3_TXP7||SATA27_TXP"
$PN"R29"84;
"G3_TXN8||SATA30_TXN"
$PN"N30"99;
"G3_RXN11||SATA33_RXN"
$PN"AN32"21;
"G3_RXN14||SATA36_RXN"
$PN"AM35"22;
"G3_TXP1||SATA21_TXP"
$PN"R23"90;
"G3_TXP4||SATA24_TXP"
$PN"R26"91;
"G3_RXP7||SATA27_RXP"
$PN"AJ30"23;
"G3_RXN8||SATA30_RXN"
$PN"AN29"24;
"G3_TXN12||SATA34_TXN"
$PN"U33"79;
"G3_TXN15||SATA37_TXN"
$PN"V36"80;
"G3_RXP1||SATA21_RXP"
$PN"AJ24"25;
"G3_RXP4||SATA24_RXP"
$PN"AJ27"26;
"G3_RXP10||SATA32_RXP"
$PN"AJ33"27;
"G3_RXP13||SATA35_RXP"
$PN"AH36"28;
"G3_TXN3||SATA23_TXN"
$PN"U27"100;
"G3_TXN6||SATA26_TXN"
$PN"W27"101;
"G3_RXN6||SATA26_RXN"
$PN"AL29"29;
"G3_TXN0||SATA20_TXN"
$PN"U24"102;
"G3_TXP8||SATA30_TXP"
$PN"N29"85;
"G3_TXP14||SATA36_TXP"
$PN"T35"75;
"G3_RXN0||SATA20_RXN"
$PN"AL23"30;
"G3_RXN3||SATA23_RXN"
$PN"AL26"31;
"G3_RXP8||SATA30_RXP"
$PN"AN30"32;
"G3_TXP11||SATA33_TXP"
$PN"N32"76;
"G3_RXN13||SATA35_RXN"
$PN"AH35"33;
"G3_TXP6||SATA26_TXP"
$PN"W26"86;
"G3_RXN10||SATA32_RXN"
$PN"AJ32"34;
"G3_TXP0||SATA20_TXP"
$PN"U23"93;
"G3_TXP3||SATA23_TXP"
$PN"U26"92;
"G3_RXP3||SATA23_RXP"
$PN"AL27"35;
"G3_RXP6||SATA26_RXP"
$PN"AL30"36;
"G3_RXP15||SATA37_RXP"
$PN"AP36"37;
"G3_TXN5||SATA25_TXN"
$PN"N27"103;
"G3_TXN11||SATA33_TXN"
$PN"N33"81;
"G3_TXN14||SATA36_TXN"
$PN"T36"82;
"G3_RXP0||SATA20_RXP"
$PN"AL24"38;
"G3_RXP12||SATA34_RXP"
$PN"AK36"39;
"G3_TXN2||SATA22_TXN"
$PN"W24"104;
"G3_RXN5||SATA25_RXN"
$PN"AN26"40;
"G3_TXP10||SATA32_TXP"
$PN"R32"87;
"G3_TXP13||SATA35_TXP"
$PN"P35"77;
%"TAP"
"6","(-3075,5800)","2","mstr_standard","I198";
;
BOM_COST"IO_SLOT"
CDS_LIB"mstr_standard"
BODY_TYPE"PLUMBING"
HDL_TAP"TRUE"
ROOM"RISER1";
"B \NAC \NWC"2;
"S \NAC"
BN"15"119;
%"TAP"
"6","(-3075,5700)","2","mstr_standard","I199";
;
BOM_COST"IO_SLOT"
CDS_LIB"mstr_standard"
BODY_TYPE"PLUMBING"
HDL_TAP"TRUE"
ROOM"RISER1";
"B \NAC \NWC"2;
"S \NAC"
BN"14"120;
%"TAP"
"6","(-3075,5400)","2","standard","I202";
;
BOM_COST"IO_SLOT"
CDS_LIB"standard"
BODY_TYPE"PLUMBING"
HDL_TAP"TRUE"
ROOM"RISER1";
"B \NAC \NWC"2;
"S \NAC"
BN"11"116;
%"TAP"
"6","(-3075,5600)","2","standard","I203";
;
BOM_COST"IO_SLOT"
CDS_LIB"standard"
BODY_TYPE"PLUMBING"
HDL_TAP"TRUE"
ROOM"RISER1";
"B \NAC \NWC"2;
"S \NAC"
BN"13"118;
%"TAP"
"6","(-3075,5500)","2","standard","I204";
;
BOM_COST"IO_SLOT"
CDS_LIB"standard"
BODY_TYPE"PLUMBING"
HDL_TAP"TRUE"
ROOM"RISER1";
"B \NAC \NWC"2;
"S \NAC"
BN"12"117;
%"TAP"
"6","(-3075,5200)","2","standard","I208";
;
BOM_COST"IO_SLOT"
CDS_LIB"standard"
BODY_TYPE"PLUMBING"
HDL_TAP"TRUE"
ROOM"RISER1";
"B \NAC \NWC"2;
"S \NAC"
BN"9"114;
%"TAP"
"6","(-3075,5300)","2","standard","I209";
;
BOM_COST"IO_SLOT"
CDS_LIB"standard"
BODY_TYPE"PLUMBING"
HDL_TAP"TRUE"
ROOM"RISER1";
"B \NAC \NWC"2;
"S \NAC"
BN"10"115;
%"TAP"
"6","(-3075,5100)","2","standard","I212";
;
BOM_COST"IO_SLOT"
CDS_LIB"standard"
BODY_TYPE"PLUMBING"
HDL_TAP"TRUE"
ROOM"RISER1";
"B \NAC \NWC"2;
"S \NAC"
BN"8"109;
%"TAP"
"6","(-3075,5000)","2","standard","I213";
;
BOM_COST"IO_SLOT"
CDS_LIB"standard"
BODY_TYPE"PLUMBING"
HDL_TAP"TRUE"
ROOM"RISER1";
"B \NAC \NWC"2;
"S \NAC"
BN"7"113;
%"TAP"
"6","(-3075,4900)","2","standard","I214";
;
BOM_COST"IO_SLOT"
CDS_LIB"standard"
BODY_TYPE"PLUMBING"
HDL_TAP"TRUE"
ROOM"RISER1";
"B \NAC \NWC"2;
"S \NAC"
BN"6"111;
%"TAP"
"6","(-3075,4700)","2","standard","I218";
;
BOM_COST"IO_SLOT"
CDS_LIB"standard"
BODY_TYPE"PLUMBING"
HDL_TAP"TRUE"
ROOM"RISER1";
"B \NAC \NWC"2;
"S \NAC"
BN"4"110;
%"TAP"
"6","(-3075,4800)","2","standard","I219";
;
BOM_COST"IO_SLOT"
CDS_LIB"standard"
BODY_TYPE"PLUMBING"
HDL_TAP"TRUE"
ROOM"RISER1";
"B \NAC \NWC"2;
"S \NAC"
BN"5"112;
%"TAP"
"6","(-3075,4600)","2","standard","I222";
;
BOM_COST"IO_SLOT"
CDS_LIB"standard"
BODY_TYPE"PLUMBING"
HDL_TAP"TRUE"
ROOM"RISER1";
"B \NAC \NWC"2;
"S \NAC"
BN"3"108;
%"TAP"
"6","(-3075,4500)","2","standard","I223";
;
BOM_COST"IO_SLOT"
CDS_LIB"standard"
BODY_TYPE"PLUMBING"
HDL_TAP"TRUE"
ROOM"RISER1";
"B \NAC \NWC"2;
"S \NAC"
BN"2"106;
%"TAP"
"6","(-3075,4400)","2","standard","I224";
;
BOM_COST"IO_SLOT"
CDS_LIB"standard"
BODY_TYPE"PLUMBING"
HDL_TAP"TRUE"
ROOM"RISER1";
"B \NAC \NWC"2;
"S \NAC"
BN"1"107;
%"TAP"
"6","(-3075,4300)","2","standard","I225";
;
BOM_COST"IO_SLOT"
CDS_LIB"standard"
BODY_TYPE"PLUMBING"
HDL_TAP"TRUE"
ROOM"RISER1";
"B \NAC \NWC"2;
"S \NAC"
BN"0"105;
%"TAP"
"6","(-3050,3125)","2","mstr_standard","I241";
;
CDS_LIB"mstr_standard"
BOM_COST"IO_SLOT"
BODY_TYPE"PLUMBING"
HDL_TAP"TRUE"
ROOM"RISER1";
"B \NAC \NWC"4;
"S \NAC"
BN"15"93;
%"TAP"
"6","(-3050,2925)","2","standard","I242";
;
CDS_LIB"standard"
BOM_COST"IO_SLOT"
BODY_TYPE"PLUMBING"
HDL_TAP"TRUE"
ROOM"RISER1";
"B \NAC \NWC"4;
"S \NAC"
BN"13"89;
%"TAP"
"6","(-3050,2825)","2","standard","I243";
;
CDS_LIB"standard"
BOM_COST"IO_SLOT"
BODY_TYPE"PLUMBING"
HDL_TAP"TRUE"
ROOM"RISER1";
"B \NAC \NWC"4;
"S \NAC"
BN"12"92;
%"TAP"
"6","(-3050,3025)","2","mstr_standard","I244";
;
CDS_LIB"mstr_standard"
BOM_COST"IO_SLOT"
BODY_TYPE"PLUMBING"
HDL_TAP"TRUE"
ROOM"RISER1";
"B \NAC \NWC"4;
"S \NAC"
BN"14"90;
%"TAP"
"6","(-3050,2725)","2","standard","I245";
;
CDS_LIB"standard"
BOM_COST"IO_SLOT"
BODY_TYPE"PLUMBING"
HDL_TAP"TRUE"
ROOM"RISER1";
"B \NAC \NWC"4;
"S \NAC"
BN"11"91;
%"TAP"
"6","(-3050,2625)","2","standard","I246";
;
CDS_LIB"standard"
BOM_COST"IO_SLOT"
BODY_TYPE"PLUMBING"
HDL_TAP"TRUE"
ROOM"RISER1";
"B \NAC \NWC"4;
"S \NAC"
BN"10"88;
%"TAP"
"6","(-3050,2425)","2","standard","I247";
;
CDS_LIB"standard"
BOM_COST"IO_SLOT"
BODY_TYPE"PLUMBING"
HDL_TAP"TRUE"
ROOM"RISER1";
"B \NAC \NWC"4;
"S \NAC"
BN"8"84;
%"TAP"
"6","(-3050,2525)","2","standard","I248";
;
CDS_LIB"standard"
BOM_COST"IO_SLOT"
BODY_TYPE"PLUMBING"
HDL_TAP"TRUE"
ROOM"RISER1";
"B \NAC \NWC"4;
"S \NAC"
BN"9"86;
%"TAP"
"6","(-3050,2325)","2","standard","I249";
;
CDS_LIB"standard"
BOM_COST"IO_SLOT"
BODY_TYPE"PLUMBING"
HDL_TAP"TRUE"
ROOM"RISER1";
"B \NAC \NWC"4;
"S \NAC"
BN"7"85;
%"TAP"
"6","(-3050,2225)","2","standard","I250";
;
CDS_LIB"standard"
BOM_COST"IO_SLOT"
BODY_TYPE"PLUMBING"
HDL_TAP"TRUE"
ROOM"RISER1";
"B \NAC \NWC"4;
"S \NAC"
BN"6"83;
%"TAP"
"6","(-3050,2125)","2","standard","I251";
;
CDS_LIB"standard"
BOM_COST"IO_SLOT"
BODY_TYPE"PLUMBING"
HDL_TAP"TRUE"
ROOM"RISER1";
"B \NAC \NWC"4;
"S \NAC"
BN"5"87;
%"TAP"
"6","(-3050,1825)","2","standard","I257";
;
CDS_LIB"standard"
BOM_COST"IO_SLOT"
BODY_TYPE"PLUMBING"
HDL_TAP"TRUE"
ROOM"RISER1";
"B \NAC \NWC"4;
"S \NAC"
BN"2"77;
%"TAP"
"6","(-3050,2025)","2","standard","I258";
;
CDS_LIB"standard"
BOM_COST"IO_SLOT"
BODY_TYPE"PLUMBING"
HDL_TAP"TRUE"
ROOM"RISER1";
"B \NAC \NWC"4;
"S \NAC"
BN"4"76;
%"TAP"
"6","(-3050,1925)","2","standard","I259";
;
CDS_LIB"standard"
BOM_COST"IO_SLOT"
BODY_TYPE"PLUMBING"
HDL_TAP"TRUE"
ROOM"RISER1";
"B \NAC \NWC"4;
"S \NAC"
BN"3"74;
%"TAP"
"6","(-3050,1725)","2","standard","I260";
;
CDS_LIB"standard"
BOM_COST"IO_SLOT"
BODY_TYPE"PLUMBING"
HDL_TAP"TRUE"
ROOM"RISER1";
"B \NAC \NWC"4;
"S \NAC"
BN"1"75;
%"TAP"
"6","(-3050,1625)","2","standard","I261";
;
CDS_LIB"standard"
BOM_COST"IO_SLOT"
BODY_TYPE"PLUMBING"
HDL_TAP"TRUE"
ROOM"RISER1";
"B \NAC \NWC"4;
"S \NAC"
BN"0"73;
%"TAP"
"6","(-6500,5800)","0","mstr_standard","I262";
;
CDS_LIB"mstr_standard"
BODY_TYPE"PLUMBING"
HDL_TAP"TRUE";
"B \NAC \NWC"5;
"S \NAC"
BN"15"56;
%"TAP"
"6","(-6500,5700)","0","mstr_standard","I263";
;
CDS_LIB"mstr_standard"
BODY_TYPE"PLUMBING"
HDL_TAP"TRUE";
"B \NAC \NWC"5;
"S \NAC"
BN"14"55;
%"TAP"
"6","(-6500,5600)","0","mstr_standard","I266";
;
CDS_LIB"mstr_standard"
BODY_TYPE"PLUMBING"
HDL_TAP"TRUE";
"B \NAC \NWC"5;
"S \NAC"
BN"13"54;
%"TAP"
"6","(-6500,5500)","0","standard","I267";
;
CDS_LIB"standard"
BODY_TYPE"PLUMBING"
HDL_TAP"TRUE";
"B \NAC \NWC"5;
"S \NAC"
BN"12"52;
%"TAP"
"6","(-6500,5400)","0","standard","I268";
;
CDS_LIB"standard"
BODY_TYPE"PLUMBING"
HDL_TAP"TRUE";
"B \NAC \NWC"5;
"S \NAC"
BN"11"50;
%"TAP"
"6","(-6500,5300)","0","standard","I271";
;
CDS_LIB"standard"
BODY_TYPE"PLUMBING"
HDL_TAP"TRUE";
"B \NAC \NWC"5;
"S \NAC"
BN"10"48;
%"TAP"
"6","(-6500,5200)","0","standard","I272";
;
CDS_LIB"standard"
BODY_TYPE"PLUMBING"
HDL_TAP"TRUE";
"B \NAC \NWC"5;
"S \NAC"
BN"9"46;
%"TAP"
"6","(-6500,5100)","0","standard","I276";
;
CDS_LIB"standard"
BODY_TYPE"PLUMBING"
HDL_TAP"TRUE";
"B \NAC \NWC"5;
"S \NAC"
BN"8"44;
%"TAP"
"6","(-6500,4900)","0","standard","I277";
;
CDS_LIB"standard"
BODY_TYPE"PLUMBING"
HDL_TAP"TRUE";
"B \NAC \NWC"5;
"S \NAC"
BN"6"64;
%"TAP"
"6","(-6500,5000)","0","standard","I278";
;
CDS_LIB"standard"
BODY_TYPE"PLUMBING"
HDL_TAP"TRUE";
"B \NAC \NWC"5;
"S \NAC"
BN"7"72;
%"TAP"
"6","(-6500,4800)","0","standard","I281";
;
CDS_LIB"standard"
BODY_TYPE"PLUMBING"
HDL_TAP"TRUE";
"B \NAC \NWC"5;
"S \NAC"
BN"5"70;
%"TAP"
"6","(-6500,4700)","0","standard","I282";
;
CDS_LIB"standard"
BODY_TYPE"PLUMBING"
HDL_TAP"TRUE";
"B \NAC \NWC"5;
"S \NAC"
BN"4"62;
%"TAP"
"6","(-6500,4600)","0","standard","I286";
;
CDS_LIB"standard"
BODY_TYPE"PLUMBING"
HDL_TAP"TRUE";
"B \NAC \NWC"5;
"S \NAC"
BN"3"68;
%"TAP"
"6","(-6500,4400)","0","standard","I287";
;
CDS_LIB"standard"
BODY_TYPE"PLUMBING"
HDL_TAP"TRUE";
"B \NAC \NWC"5;
"S \NAC"
BN"1"66;
%"TAP"
"6","(-6500,4500)","0","standard","I288";
;
CDS_LIB"standard"
BODY_TYPE"PLUMBING"
HDL_TAP"TRUE";
"B \NAC \NWC"5;
"S \NAC"
BN"2"60;
%"TAP"
"6","(-6500,4300)","0","standard","I291";
;
CDS_LIB"standard"
BODY_TYPE"PLUMBING"
HDL_TAP"TRUE";
"B \NAC \NWC"5;
"S \NAC"
BN"0"58;
%"TAP"
"6","(-6475,3125)","0","standard","I296";
;
CDS_LIB"standard"
BODY_TYPE"PLUMBING"
HDL_TAP"TRUE";
"B \NAC \NWC"7;
"S \NAC"
BN"15"38;
%"TAP"
"6","(-6475,2925)","0","standard","I298";
;
CDS_LIB"standard"
BODY_TYPE"PLUMBING"
HDL_TAP"TRUE";
"B \NAC \NWC"7;
"S \NAC"
BN"13"13;
%"TAP"
"6","(-6475,3025)","0","standard","I299";
;
CDS_LIB"standard"
BODY_TYPE"PLUMBING"
HDL_TAP"TRUE";
"B \NAC \NWC"7;
"S \NAC"
BN"14"25;
%"TAP"
"6","(-6475,2825)","0","standard","I300";
;
CDS_LIB"standard"
BODY_TYPE"PLUMBING"
HDL_TAP"TRUE";
"B \NAC \NWC"7;
"S \NAC"
BN"12"35;
%"TAP"
"6","(-6475,2725)","0","standard","I303";
;
CDS_LIB"standard"
BODY_TYPE"PLUMBING"
HDL_TAP"TRUE";
"B \NAC \NWC"7;
"S \NAC"
BN"11"26;
%"TAP"
"6","(-6475,2625)","0","standard","I304";
;
CDS_LIB"standard"
BODY_TYPE"PLUMBING"
HDL_TAP"TRUE";
"B \NAC \NWC"7;
"S \NAC"
BN"10"14;
%"TAP"
"6","(-6475,2425)","0","standard","I308";
;
CDS_LIB"standard"
BODY_TYPE"PLUMBING"
HDL_TAP"TRUE";
"B \NAC \NWC"7;
"S \NAC"
BN"8"23;
%"TAP"
"6","(-6475,2525)","0","standard","I309";
;
CDS_LIB"standard"
BODY_TYPE"PLUMBING"
HDL_TAP"TRUE";
"B \NAC \NWC"7;
"S \NAC"
BN"9"36;
%"TAP"
"6","(-6475,2325)","0","standard","I310";
;
CDS_LIB"standard"
BODY_TYPE"PLUMBING"
HDL_TAP"TRUE";
"B \NAC \NWC"7;
"S \NAC"
BN"7"32;
%"TAP"
"6","(-6475,2225)","0","standard","I313";
;
CDS_LIB"standard"
BODY_TYPE"PLUMBING"
HDL_TAP"TRUE";
"B \NAC \NWC"7;
"S \NAC"
BN"6"20;
%"TAP"
"6","(-6475,2125)","0","standard","I314";
;
CDS_LIB"standard"
BODY_TYPE"PLUMBING"
HDL_TAP"TRUE";
"B \NAC \NWC"7;
"S \NAC"
BN"5"27;
%"TAP"
"6","(-6475,2025)","0","standard","I320";
;
CDS_LIB"standard"
BODY_TYPE"PLUMBING"
HDL_TAP"TRUE";
"B \NAC \NWC"7;
"S \NAC"
BN"4"16;
%"TAP"
"6","(-6475,1925)","0","standard","I321";
;
CDS_LIB"standard"
BODY_TYPE"PLUMBING"
HDL_TAP"TRUE";
"B \NAC \NWC"7;
"S \NAC"
BN"3"39;
%"TAP"
"6","(-6475,1825)","0","standard","I322";
;
CDS_LIB"standard"
BODY_TYPE"PLUMBING"
HDL_TAP"TRUE";
"B \NAC \NWC"7;
"S \NAC"
BN"2"28;
%"TAP"
"6","(-6475,1725)","0","standard","I325";
;
CDS_LIB"standard"
BODY_TYPE"PLUMBING"
HDL_TAP"TRUE";
"B \NAC \NWC"7;
"S \NAC"
BN"1"15;
%"TAP"
"6","(-6475,1625)","0","standard","I327";
;
CDS_LIB"standard"
BODY_TYPE"PLUMBING"
HDL_TAP"TRUE";
"B \NAC \NWC"7;
"S \NAC"
BN"0"37;
%"TAP"
"6","(-6650,5750)","0","mstr_standard","I398";
;
CDS_LIB"mstr_standard"
BODY_TYPE"PLUMBING"
HDL_TAP"TRUE";
"B \NAC \NWC"6;
"S \NAC"
BN"15"53;
%"TAP"
"6","(-6650,5650)","0","mstr_standard","I399";
;
CDS_LIB"mstr_standard"
BODY_TYPE"PLUMBING"
HDL_TAP"TRUE";
"B \NAC \NWC"6;
"S \NAC"
BN"14"51;
%"TAP"
"6","(-6650,5450)","0","standard","I400";
;
CDS_LIB"standard"
BODY_TYPE"PLUMBING"
HDL_TAP"TRUE";
"B \NAC \NWC"6;
"S \NAC"
BN"12"47;
%"TAP"
"6","(-6650,5550)","0","standard","I401";
;
CDS_LIB"standard"
BODY_TYPE"PLUMBING"
HDL_TAP"TRUE";
"B \NAC \NWC"6;
"S \NAC"
BN"13"49;
%"TAP"
"6","(-6650,5150)","0","standard","I402";
;
CDS_LIB"standard"
BODY_TYPE"PLUMBING"
HDL_TAP"TRUE";
"B \NAC \NWC"6;
"S \NAC"
BN"9"42;
%"TAP"
"6","(-6650,5350)","0","standard","I403";
;
CDS_LIB"standard"
BODY_TYPE"PLUMBING"
HDL_TAP"TRUE";
"B \NAC \NWC"6;
"S \NAC"
BN"11"45;
%"TAP"
"6","(-6650,5250)","0","standard","I404";
;
CDS_LIB"standard"
BODY_TYPE"PLUMBING"
HDL_TAP"TRUE";
"B \NAC \NWC"6;
"S \NAC"
BN"10"43;
%"TAP"
"6","(-6650,4950)","0","standard","I405";
;
CDS_LIB"standard"
BODY_TYPE"PLUMBING"
HDL_TAP"TRUE";
"B \NAC \NWC"6;
"S \NAC"
BN"7"71;
%"TAP"
"6","(-6650,5050)","0","standard","I406";
;
CDS_LIB"standard"
BODY_TYPE"PLUMBING"
HDL_TAP"TRUE";
"B \NAC \NWC"6;
"S \NAC"
BN"8"41;
%"TAP"
"6","(-6650,4850)","0","standard","I407";
;
CDS_LIB"standard"
BODY_TYPE"PLUMBING"
HDL_TAP"TRUE";
"B \NAC \NWC"6;
"S \NAC"
BN"6"63;
%"TAP"
"6","(-6650,4650)","0","standard","I408";
;
CDS_LIB"standard"
BODY_TYPE"PLUMBING"
HDL_TAP"TRUE";
"B \NAC \NWC"6;
"S \NAC"
BN"4"61;
%"TAP"
"6","(-6650,4750)","0","standard","I409";
;
CDS_LIB"standard"
BODY_TYPE"PLUMBING"
HDL_TAP"TRUE";
"B \NAC \NWC"6;
"S \NAC"
BN"5"69;
%"TAP"
"6","(-6650,4450)","0","standard","I410";
;
CDS_LIB"standard"
BODY_TYPE"PLUMBING"
HDL_TAP"TRUE";
"B \NAC \NWC"6;
"S \NAC"
BN"2"59;
%"TAP"
"6","(-6650,4550)","0","standard","I411";
;
CDS_LIB"standard"
BODY_TYPE"PLUMBING"
HDL_TAP"TRUE";
"B \NAC \NWC"6;
"S \NAC"
BN"3"67;
%"TAP"
"6","(-6650,4350)","0","standard","I412";
;
CDS_LIB"standard"
BODY_TYPE"PLUMBING"
HDL_TAP"TRUE";
"B \NAC \NWC"6;
"S \NAC"
BN"1"65;
%"TAP"
"6","(-6650,4250)","0","standard","I413";
;
CDS_LIB"standard"
BODY_TYPE"PLUMBING"
HDL_TAP"TRUE";
"B \NAC \NWC"6;
"S \NAC"
BN"0"57;
%"TAP"
"6","(-2925,5750)","2","mstr_standard","I416";
;
CDS_LIB"mstr_standard"
BOM_COST"IO_SLOT"
BODY_TYPE"PLUMBING"
HDL_TAP"TRUE"
ROOM"RISER1";
"B \NAC \NWC"1;
"S \NAC"
BN"15"128;
%"TAP"
"6","(-2925,5650)","2","mstr_standard","I417";
;
BOM_COST"IO_SLOT"
CDS_LIB"mstr_standard"
BODY_TYPE"PLUMBING"
HDL_TAP"TRUE"
ROOM"RISER1";
"B \NAC \NWC"1;
"S \NAC"
BN"14"127;
%"TAP"
"6","(-2925,5250)","2","standard","I418";
;
BOM_COST"IO_SLOT"
CDS_LIB"standard"
BODY_TYPE"PLUMBING"
HDL_TAP"TRUE"
ROOM"RISER1";
"B \NAC \NWC"1;
"S \NAC"
BN"10"123;
%"TAP"
"6","(-2925,5150)","2","standard","I419";
;
BOM_COST"IO_SLOT"
CDS_LIB"standard"
BODY_TYPE"PLUMBING"
HDL_TAP"TRUE"
ROOM"RISER1";
"B \NAC \NWC"1;
"S \NAC"
BN"9"122;
%"TAP"
"6","(-2925,5350)","2","standard","I420";
;
BOM_COST"IO_SLOT"
CDS_LIB"standard"
BODY_TYPE"PLUMBING"
HDL_TAP"TRUE"
ROOM"RISER1";
"B \NAC \NWC"1;
"S \NAC"
BN"11"124;
%"TAP"
"6","(-2925,5450)","2","standard","I421";
;
BOM_COST"IO_SLOT"
CDS_LIB"standard"
BODY_TYPE"PLUMBING"
HDL_TAP"TRUE"
ROOM"RISER1";
"B \NAC \NWC"1;
"S \NAC"
BN"12"125;
%"TAP"
"6","(-2925,5550)","2","standard","I422";
;
BOM_COST"IO_SLOT"
CDS_LIB"standard"
BODY_TYPE"PLUMBING"
HDL_TAP"TRUE"
ROOM"RISER1";
"B \NAC \NWC"1;
"S \NAC"
BN"13"126;
%"TAP"
"6","(-2925,4850)","2","standard","I423";
;
BOM_COST"IO_SLOT"
CDS_LIB"standard"
BODY_TYPE"PLUMBING"
HDL_TAP"TRUE"
ROOM"RISER1";
"B \NAC \NWC"1;
"S \NAC"
BN"6"132;
%"TAP"
"6","(-2925,4650)","2","standard","I424";
;
BOM_COST"IO_SLOT"
CDS_LIB"standard"
BODY_TYPE"PLUMBING"
HDL_TAP"TRUE"
ROOM"RISER1";
"B \NAC \NWC"1;
"S \NAC"
BN"4"131;
%"TAP"
"6","(-2925,4750)","2","standard","I425";
;
BOM_COST"IO_SLOT"
CDS_LIB"standard"
BODY_TYPE"PLUMBING"
HDL_TAP"TRUE"
ROOM"RISER1";
"B \NAC \NWC"1;
"S \NAC"
BN"5"135;
%"TAP"
"6","(-2925,5050)","2","standard","I426";
;
BOM_COST"IO_SLOT"
CDS_LIB"standard"
BODY_TYPE"PLUMBING"
HDL_TAP"TRUE"
ROOM"RISER1";
"B \NAC \NWC"1;
"S \NAC"
BN"8"121;
%"TAP"
"6","(-2925,4950)","2","standard","I427";
;
BOM_COST"IO_SLOT"
CDS_LIB"standard"
BODY_TYPE"PLUMBING"
HDL_TAP"TRUE"
ROOM"RISER1";
"B \NAC \NWC"1;
"S \NAC"
BN"7"136;
%"TAP"
"6","(-2925,4250)","2","standard","I428";
;
BOM_COST"IO_SLOT"
CDS_LIB"standard"
BODY_TYPE"PLUMBING"
HDL_TAP"TRUE"
ROOM"RISER1";
"B \NAC \NWC"1;
"S \NAC"
BN"0"129;
%"TAP"
"6","(-2925,4550)","2","standard","I429";
;
BOM_COST"IO_SLOT"
CDS_LIB"standard"
BODY_TYPE"PLUMBING"
HDL_TAP"TRUE"
ROOM"RISER1";
"B \NAC \NWC"1;
"S \NAC"
BN"3"134;
%"TAP"
"6","(-2925,4450)","2","standard","I430";
;
BOM_COST"IO_SLOT"
CDS_LIB"standard"
BODY_TYPE"PLUMBING"
HDL_TAP"TRUE"
ROOM"RISER1";
"B \NAC \NWC"1;
"S \NAC"
BN"2"130;
%"TAP"
"6","(-2925,4350)","2","standard","I431";
;
CDS_LIB"standard"
BOM_COST"IO_SLOT"
BODY_TYPE"PLUMBING"
HDL_TAP"TRUE"
ROOM"RISER1";
"B \NAC \NWC"1;
"S \NAC"
BN"1"133;
%"TAP"
"6","(-2900,3075)","2","mstr_standard","I433";
;
BOM_COST"IO_SLOT"
CDS_LIB"mstr_standard"
BODY_TYPE"PLUMBING"
HDL_TAP"TRUE"
ROOM"RISER1";
"B \NAC \NWC"3;
"S \NAC"
BN"15"102;
%"TAP"
"6","(-2900,2975)","2","mstr_standard","I434";
;
CDS_LIB"mstr_standard"
BOM_COST"IO_SLOT"
BODY_TYPE"PLUMBING"
HDL_TAP"TRUE"
ROOM"RISER1";
"B \NAC \NWC"3;
"S \NAC"
BN"14"98;
%"TAP"
"6","(-2900,2875)","2","standard","I435";
;
CDS_LIB"standard"
BOM_COST"IO_SLOT"
BODY_TYPE"PLUMBING"
HDL_TAP"TRUE"
ROOM"RISER1";
"B \NAC \NWC"3;
"S \NAC"
BN"13"104;
%"TAP"
"6","(-2900,2775)","2","standard","I436";
;
CDS_LIB"standard"
BOM_COST"IO_SLOT"
BODY_TYPE"PLUMBING"
HDL_TAP"TRUE"
ROOM"RISER1";
"B \NAC \NWC"3;
"S \NAC"
BN"12"100;
%"TAP"
"6","(-2900,2675)","2","standard","I437";
;
CDS_LIB"standard"
BOM_COST"IO_SLOT"
BODY_TYPE"PLUMBING"
HDL_TAP"TRUE"
ROOM"RISER1";
"B \NAC \NWC"3;
"S \NAC"
BN"11"95;
%"TAP"
"6","(-2900,2575)","2","standard","I438";
;
CDS_LIB"standard"
BOM_COST"IO_SLOT"
BODY_TYPE"PLUMBING"
HDL_TAP"TRUE"
ROOM"RISER1";
"B \NAC \NWC"3;
"S \NAC"
BN"10"103;
%"TAP"
"6","(-2900,2475)","2","standard","I439";
;
CDS_LIB"standard"
BOM_COST"IO_SLOT"
BODY_TYPE"PLUMBING"
HDL_TAP"TRUE"
ROOM"RISER1";
"B \NAC \NWC"3;
"S \NAC"
BN"9"101;
%"TAP"
"6","(-2900,2375)","2","standard","I440";
;
CDS_LIB"standard"
BOM_COST"IO_SLOT"
BODY_TYPE"PLUMBING"
HDL_TAP"TRUE"
ROOM"RISER1";
"B \NAC \NWC"3;
"S \NAC"
BN"8"96;
%"TAP"
"6","(-2900,2275)","2","standard","I441";
;
CDS_LIB"standard"
BOM_COST"IO_SLOT"
BODY_TYPE"PLUMBING"
HDL_TAP"TRUE"
ROOM"RISER1";
"B \NAC \NWC"3;
"S \NAC"
BN"7"99;
%"TAP"
"6","(-2900,2175)","2","standard","I442";
;
CDS_LIB"standard"
BOM_COST"IO_SLOT"
BODY_TYPE"PLUMBING"
HDL_TAP"TRUE"
ROOM"RISER1";
"B \NAC \NWC"3;
"S \NAC"
BN"6"94;
%"TAP"
"6","(-2900,2075)","2","standard","I443";
;
CDS_LIB"standard"
BOM_COST"IO_SLOT"
BODY_TYPE"PLUMBING"
HDL_TAP"TRUE"
ROOM"RISER1";
"B \NAC \NWC"3;
"S \NAC"
BN"5"97;
%"TAP"
"6","(-2900,1975)","2","standard","I444";
;
CDS_LIB"standard"
BOM_COST"IO_SLOT"
BODY_TYPE"PLUMBING"
HDL_TAP"TRUE"
ROOM"RISER1";
"B \NAC \NWC"3;
"S \NAC"
BN"4"81;
%"TAP"
"6","(-2900,1875)","2","standard","I445";
;
CDS_LIB"standard"
BOM_COST"IO_SLOT"
BODY_TYPE"PLUMBING"
HDL_TAP"TRUE"
ROOM"RISER1";
"B \NAC \NWC"3;
"S \NAC"
BN"3"79;
%"TAP"
"6","(-2900,1675)","2","standard","I446";
;
BOM_COST"IO_SLOT"
CDS_LIB"standard"
BODY_TYPE"PLUMBING"
HDL_TAP"TRUE"
ROOM"RISER1";
"B \NAC \NWC"3;
"S \NAC"
BN"1"82;
%"TAP"
"6","(-2900,1775)","2","standard","I447";
;
CDS_LIB"standard"
BOM_COST"IO_SLOT"
BODY_TYPE"PLUMBING"
HDL_TAP"TRUE"
ROOM"RISER1";
"B \NAC \NWC"3;
"S \NAC"
BN"2"78;
%"TAP"
"6","(-2900,1575)","2","standard","I448";
;
CDS_LIB"standard"
BOM_COST"IO_SLOT"
BODY_TYPE"PLUMBING"
HDL_TAP"TRUE"
ROOM"RISER1";
"B \NAC \NWC"3;
"S \NAC"
BN"0"80;
%"TAP"
"6","(-6625,3075)","0","mstr_standard","I449";
;
CDS_LIB"mstr_standard"
BODY_TYPE"PLUMBING"
HDL_TAP"TRUE";
"B \NAC \NWC"8;
"S \NAC"
BN"15"30;
%"TAP"
"6","(-6625,2975)","0","mstr_standard","I450";
;
CDS_LIB"mstr_standard"
BODY_TYPE"PLUMBING"
HDL_TAP"TRUE";
"B \NAC \NWC"8;
"S \NAC"
BN"14"17;
%"TAP"
"6","(-6625,2875)","0","standard","I451";
;
CDS_LIB"standard"
BODY_TYPE"PLUMBING"
HDL_TAP"TRUE";
"B \NAC \NWC"8;
"S \NAC"
BN"13"9;
%"TAP"
"6","(-6625,2775)","0","standard","I452";
;
CDS_LIB"standard"
BODY_TYPE"PLUMBING"
HDL_TAP"TRUE";
"B \NAC \NWC"8;
"S \NAC"
BN"12"31;
%"TAP"
"6","(-6625,2675)","0","standard","I453";
;
CDS_LIB"standard"
BODY_TYPE"PLUMBING"
HDL_TAP"TRUE";
"B \NAC \NWC"8;
"S \NAC"
BN"11"18;
%"TAP"
"6","(-6625,2475)","0","standard","I454";
;
CDS_LIB"standard"
BODY_TYPE"PLUMBING"
HDL_TAP"TRUE";
"B \NAC \NWC"8;
"S \NAC"
BN"9"29;
%"TAP"
"6","(-6625,2575)","0","standard","I455";
;
CDS_LIB"standard"
BODY_TYPE"PLUMBING"
HDL_TAP"TRUE";
"B \NAC \NWC"8;
"S \NAC"
BN"10"40;
%"TAP"
"6","(-6625,2375)","0","standard","I456";
;
CDS_LIB"standard"
BODY_TYPE"PLUMBING"
HDL_TAP"TRUE";
"B \NAC \NWC"8;
"S \NAC"
BN"8"19;
%"TAP"
"6","(-6625,2275)","0","standard","I457";
;
CDS_LIB"standard"
BODY_TYPE"PLUMBING"
HDL_TAP"TRUE";
"B \NAC \NWC"8;
"S \NAC"
BN"7"24;
%"TAP"
"6","(-6625,2175)","0","standard","I458";
;
CDS_LIB"standard"
BODY_TYPE"PLUMBING"
HDL_TAP"TRUE";
"B \NAC \NWC"8;
"S \NAC"
BN"6"12;
%"TAP"
"6","(-6625,1975)","0","standard","I459";
;
CDS_LIB"standard"
BODY_TYPE"PLUMBING"
HDL_TAP"TRUE";
"B \NAC \NWC"8;
"S \NAC"
BN"4"21;
%"TAP"
"6","(-6625,2075)","0","standard","I460";
;
CDS_LIB"standard"
BODY_TYPE"PLUMBING"
HDL_TAP"TRUE";
"B \NAC \NWC"8;
"S \NAC"
BN"5"34;
%"TAP"
"6","(-6625,1875)","0","standard","I461";
;
CDS_LIB"standard"
BODY_TYPE"PLUMBING"
HDL_TAP"TRUE";
"B \NAC \NWC"8;
"S \NAC"
BN"3"10;
%"TAP"
"6","(-6625,1775)","0","standard","I462";
;
CDS_LIB"standard"
BODY_TYPE"PLUMBING"
HDL_TAP"TRUE";
"B \NAC \NWC"8;
"S \NAC"
BN"2"33;
%"TAP"
"6","(-6625,1575)","0","standard","I463";
;
CDS_LIB"standard"
BODY_TYPE"PLUMBING"
HDL_TAP"TRUE";
"B \NAC \NWC"8;
"S \NAC"
BN"0"11;
%"TAP"
"6","(-6625,1675)","0","standard","I464";
;
CDS_LIB"standard"
BODY_TYPE"PLUMBING"
HDL_TAP"TRUE";
"B \NAC \NWC"8;
"S \NAC"
BN"1"22;
END.
